# T6G (Grand Teton) — schematic netlist excerpt (pin names and nets, part order shuffled) for the footprints in the layout excerpt that follows; sources: Cadence DE-HDL packaged netlist, KiCad conversion of 04192023_DAF0TMB3IC0_F0TG_MB_C_brd_V02_OCP.brd

C6753  Q_CAP_DIFFBUS  DIFF BUS_0.22UF 6.3V 20% X6S  pkg C0201  page 352 : \1\ = P5E_CPU1_P3_TX_BUF_C_DP<14> ; \2\ = P5E_CPU1_P3_TX_BUF_DP<14>
PR412  Q_RES  0 5% CHIP  pkg 0402LF  page 207 : A = PVDD11_S3_P0_TEMP1 ; B = GND

U41  PI3CSW12ZUAEX  IC  pkg UQFN10_0-5_2X1-5  page 186
  \1d+\  = SMB_RT_CPU1_P3_ROM_MUX_1D_SCL
  \1d-\  = SMB_RT_CPU1_P3_ROM_MUX_1D_SDA
  \2d+\  = SMB_RT_CPU1_P3_ROM_MUX_2D_SCL
  \2d-\  = SMB_RT_CPU1_P3_ROM_MUX_2D_SDA
  GND  = GND
  \oe#\  = RT_ROM_MUX3_OE_N
  \d-\  = SMB_RT_CPU1_P3_ROM_R_SDA
  \d+\  = SMB_RT_CPU1_P3_ROM_R_SCL
  S  = FM_SMB_RT_ROM_MUX3_SEL
  VDD  = P3V3_AUX

(kicad_pcb
	(version 20260206)
	(generator "pcbnew")
	(generator_version "10.0")
	(general
		(thickness 1.6)
		(legacy_teardrops no)
	)
	(paper "A4")
	(title_block
		(title "04192023_DAF0TMB3IC0_F0TG_MB_C_brd_V02_OCP.brd")
		(comment 1 "Grand Teton / footprints 7272-7274 of 8354")
	)
	(layers
		(0 "F.Cu" signal "TOP")
		(4 "In1.Cu" signal "GND")
		(6 "In2.Cu" signal "IN1")
		(8 "In3.Cu" signal "GND1")
		(10 "In4.Cu" signal "IN2")
		(12 "In5.Cu" signal "GND2")
		(14 "In6.Cu" signal "IN3")
		(16 "In7.Cu" signal "GND3")
		(18 "In8.Cu" signal "VCC")
		(20 "In9.Cu" signal "VCC1")
		(22 "In10.Cu" signal "GND4")
		(24 "In11.Cu" signal "IN4")
		(26 "In12.Cu" signal "GND5")
		(28 "In13.Cu" signal "IN5")
		(30 "In14.Cu" signal "GND6")
		(32 "In15.Cu" signal "IN6")
		(34 "In16.Cu" signal "GND7")
		(2 "B.Cu" signal "BOTTOM")
		(9 "F.Adhes" user "F.Adhesive")
		(11 "B.Adhes" user "B.Adhesive")
		(13 "F.Paste" user "Package Geometry/Pastemask Top")
		(15 "B.Paste" user "Package Geometry/Pastemask Bottom")
		(5 "F.SilkS" user "Ref Des/Silkscreen Top")
		(7 "B.SilkS" user "Ref Des/Silkscreen Bottom")
		(1 "F.Mask" user "Board Geometry/Soldermask Top")
		(3 "B.Mask" user "Board Geometry/Soldermask Bottom")
		(17 "Dwgs.User" user "User.Drawings")
		(19 "Cmts.User" user "User.Comments")
		(21 "Eco1.User" user "User.Eco1")
		(23 "Eco2.User" user "User.Eco2")
		(25 "Edge.Cuts" user "Board Geometry/Outline")
		(27 "Margin" user)
		(31 "F.CrtYd" user "Package Geometry/Place Bound Top")
		(29 "B.CrtYd" user "Package Geometry/Place Bound Bottom")
		(35 "F.Fab" user "Ref Des/Assembly Top")
		(33 "B.Fab" user "Ref Des/Assembly Bottom")
	)
	(footprint ""
		(layer "B.Cu")
		(at 420.51478 -359.736136)
		(property "Reference" "PR412"
			(at 0 0 0)
			(layer "B.SilkS")
			(hide yes)
			(effects
				(font
					(size 1.27 1.27)
				)
				(justify mirror)
			)
		)
		(property "Value" ""
			(at 0 0 0)
			(layer "B.Fab")
			(effects
				(font
					(size 1.27 1.27)
				)
				(justify mirror)
			)
		)
		(duplicate_pad_numbers_are_jumpers no)
		(fp_line
			(start -0.7874 -0.4064)
			(end -0.7874 0.4064)
			(stroke
				(width 0.1524)
				(type default)
			)
			(layer "B.SilkS")
		)
		(fp_line
			(start -0.7874 0.4064)
			(end 0.7874 0.4064)
			(stroke
				(width 0.1524)
				(type default)
			)
			(layer "B.SilkS")
		)
		(fp_line
			(start 0.7874 -0.4064)
			(end -0.7874 -0.4064)
			(stroke
				(width 0.1524)
				(type default)
			)
			(layer "B.SilkS")
		)
		(fp_line
			(start 0.7874 0.4064)
			(end 0.7874 -0.4064)
			(stroke
				(width 0.1524)
				(type default)
			)
			(layer "B.SilkS")
		)
		(fp_line
			(start -0.67945 -0.3048)
			(end -0.67945 0.3048)
			(stroke
				(width 0.1)
				(type default)
			)
			(layer "B.Fab")
		)
		(fp_line
			(start -0.67945 0.3048)
			(end -0.120396 0.3048)
			(stroke
				(width 0.1)
				(type default)
			)
			(layer "B.Fab")
		)
		(fp_line
			(start -0.12065 -0.3048)
			(end -0.67945 -0.3048)
			(stroke
				(width 0.1)
				(type default)
			)
			(layer "B.Fab")
		)
		(fp_line
			(start -0.12065 -0.2794)
			(end -0.12065 -0.3048)
			(stroke
				(width 0.1)
				(type default)
			)
			(layer "B.Fab")
		)
		(fp_line
			(start -0.120396 0.2794)
			(end 0.12065 0.2794)
			(stroke
				(width 0.1)
				(type default)
			)
			(layer "B.Fab")
		)
		(fp_line
			(start -0.120396 0.3048)
			(end -0.120396 0.2794)
			(stroke
				(width 0.1)
				(type default)
			)
			(layer "B.Fab")
		)
		(fp_line
			(start 0.12065 -0.305054)
			(end 0.12065 -0.2794)
			(stroke
				(width 0.1)
				(type default)
			)
			(layer "B.Fab")
		)
		(fp_line
			(start 0.12065 -0.2794)
			(end -0.12065 -0.2794)
			(stroke
				(width 0.1)
				(type default)
			)
			(layer "B.Fab")
		)
		(fp_line
			(start 0.12065 0.2794)
			(end 0.12065 0.3048)
			(stroke
				(width 0.1)
				(type default)
			)
			(layer "B.Fab")
		)
		(fp_line
			(start 0.12065 0.3048)
			(end 0.67945 0.3048)
			(stroke
				(width 0.1)
				(type default)
			)
			(layer "B.Fab")
		)
		(fp_line
			(start 0.67945 -0.305054)
			(end 0.12065 -0.305054)
			(stroke
				(width 0.1)
				(type default)
			)
			(layer "B.Fab")
		)
		(fp_line
			(start 0.67945 0.3048)
			(end 0.67945 -0.305054)
			(stroke
				(width 0.1)
				(type default)
			)
			(layer "B.Fab")
		)
		(pad "1" smd circle
			(at 0.40005 0 180)
			(size 0 0)
			(layers "B.Cu" "B.Mask" "B.Paste")
			(net "PVDD11_S3_P0_TEMP1")
		)
		(pad "2" smd circle
			(at -0.40005 0 180)
			(size 0 0)
			(layers "B.Cu" "B.Mask" "B.Paste")
			(net "GND")
		)
	)
	(footprint ""
		(layer "B.Cu")
		(at 160.200086 -408.517344 90)
		(property "Reference" "C6753"
			(at 0 0 90)
			(layer "B.SilkS")
			(hide yes)
			(effects
				(font
					(size 1.27 1.27)
				)
				(justify mirror)
			)
		)
		(property "Value" ""
			(at 0 0 90)
			(layer "B.Fab")
			(effects
				(font
					(size 1.27 1.27)
				)
				(justify mirror)
			)
		)
		(duplicate_pad_numbers_are_jumpers no)
		(fp_line
			(start 0.299974 -0.150114)
			(end -0.299974 -0.150114)
			(stroke
				(width 0.1)
				(type default)
			)
			(layer "B.Fab")
		)
		(fp_line
			(start -0.299974 -0.150114)
			(end -0.299974 0.150114)
			(stroke
				(width 0.1)
				(type default)
			)
			(layer "B.Fab")
		)
		(fp_line
			(start 0.299974 0.150114)
			(end 0.299974 -0.150114)
			(stroke
				(width 0.1)
				(type default)
			)
			(layer "B.Fab")
		)
		(fp_line
			(start -0.299974 0.150114)
			(end 0.299974 0.150114)
			(stroke
				(width 0.1)
				(type default)
			)
			(layer "B.Fab")
		)
		(pad "1" smd rect
			(at 0.2667 0 270)
			(size 0.3048 0.381)
			(layers "B.Cu" "B.Mask" "B.Paste")
			(net "P5E_CPU1_P3_TX_BUF_C_DP<14>")
		)
		(pad "2" smd rect
			(at -0.2667 0 270)
			(size 0.3048 0.381)
			(layers "B.Cu" "B.Mask" "B.Paste")
			(net "P5E_CPU1_P3_TX_BUF_DP<14>")
		)
	)
	(footprint ""
		(layer "B.Cu")
		(at 168.44645 -424.117262 -90)
		(property "Reference" "U41"
			(at -3.056128 0.105918 0)
			(unlocked yes)
			(layer "B.SilkS")
			(effects
				(font
					(size 0.7874 0.5842)
					(thickness 0.1524)
				)
				(justify mirror)
			)
		)
		(property "Value" ""
			(at 0 0 90)
			(layer "B.Fab")
			(effects
				(font
					(size 1.27 1.27)
				)
				(justify mirror)
			)
		)
		(duplicate_pad_numbers_are_jumpers no)
		(fp_line
			(start -1.03378 1.284478)
			(end 1.03378 1.284478)
			(stroke
				(width 0.1524)
				(type default)
			)
			(layer "B.SilkS")
		)
		(fp_line
			(start 1.03378 1.284478)
			(end 1.03378 -1.284478)
			(stroke
				(width 0.1524)
				(type default)
			)
			(layer "B.SilkS")
		)
		(fp_line
			(start -1.03378 -1.284478)
			(end -1.03378 1.284478)
			(stroke
				(width 0.1524)
				(type default)
			)
			(layer "B.SilkS")
		)
		(fp_line
			(start 1.03378 -1.284478)
			(end -1.03378 -1.284478)
			(stroke
				(width 0.1524)
				(type default)
			)
			(layer "B.SilkS")
		)
		(fp_poly
			(pts
				(xy 1.258316 -1.470152) (xy 1.86182 -1.775714) (xy 1.375918 -2.13614)
			)
			(stroke
				(width 0)
				(type default)
			)
			(fill yes)
			(layer "B.SilkS")
		)
		(fp_line
			(start -0.774954 1.02489)
			(end 0.774954 1.02489)
			(stroke
				(width 0.1)
				(type default)
			)
			(layer "B.Fab")
		)
		(fp_line
			(start 0.774954 1.02489)
			(end 0.774954 -1.02489)
			(stroke
				(width 0.1)
				(type default)
			)
			(layer "B.Fab")
		)
		(fp_line
			(start -0.774954 -1.02489)
			(end -0.774954 1.02489)
			(stroke
				(width 0.1)
				(type default)
			)
			(layer "B.Fab")
		)
		(fp_line
			(start 0.774954 -1.02489)
			(end -0.774954 -1.02489)
			(stroke
				(width 0.1)
				(type default)
			)
			(layer "B.Fab")
		)
		(fp_poly
			(pts
				(xy 1.201674 -0.750062) (xy 1.806702 -0.447548) (xy 1.806702 -1.052576)
			)
			(stroke
				(width 0)
				(type default)
			)
			(fill yes)
			(layer "B.Fab")
		)
		(pad "1" smd rect
			(at 0.64008 -0.750062)
			(size 0.3048 0.5334)
			(layers "B.Cu" "B.Mask" "B.Paste")
			(net "SMB_RT_CPU1_P3_ROM_MUX_1D_SCL")
		)
		(pad "2" smd rect
			(at 0.64008 -0.249936)
			(size 0.254 0.5334)
			(layers "B.Cu" "B.Mask" "B.Paste")
			(net "SMB_RT_CPU1_P3_ROM_MUX_1D_SDA")
		)
		(pad "3" smd rect
			(at 0.64008 0.249936)
			(size 0.254 0.5334)
			(layers "B.Cu" "B.Mask" "B.Paste")
			(net "SMB_RT_CPU1_P3_ROM_MUX_2D_SCL")
		)
		(pad "4" smd rect
			(at 0.64008 0.750062)
			(size 0.3048 0.5334)
			(layers "B.Cu" "B.Mask" "B.Paste")
			(net "SMB_RT_CPU1_P3_ROM_MUX_2D_SDA")
		)
		(pad "5" smd rect
			(at 0 0.839978 90)
			(size 0.3302 0.635)
			(layers "B.Cu" "B.Mask" "B.Paste")
			(net "GND")
		)
		(pad "6" smd rect
			(at -0.64008 0.750062)
			(size 0.3048 0.5334)
			(layers "B.Cu" "B.Mask" "B.Paste")
			(net "RT_ROM_MUX3_OE_N")
		)
		(pad "7" smd rect
			(at -0.64008 0.249936)
			(size 0.254 0.5334)
			(layers "B.Cu" "B.Mask" "B.Paste")
			(net "SMB_RT_CPU1_P3_ROM_R_SDA")
		)
		(pad "8" smd rect
			(at -0.64008 -0.249936)
			(size 0.254 0.5334)
			(layers "B.Cu" "B.Mask" "B.Paste")
			(net "SMB_RT_CPU1_P3_ROM_R_SCL")
		)
		(pad "9" smd rect
			(at -0.64008 -0.750062)
			(size 0.3048 0.5334)
			(layers "B.Cu" "B.Mask" "B.Paste")
			(net "FM_SMB_RT_ROM_MUX3_SEL")
		)
		(pad "10" smd rect
			(at 0 -0.839978 90)
			(size 0.3302 0.635)
			(layers "B.Cu" "B.Mask" "B.Paste")
			(net "P3V3_AUX")
		)
	)
)
